(kicad_pcb
	(version 20241229)
	(generator "pcbnew")
	(generator_version "9.0")
	(general
		(thickness 1.62)
		(legacy_teardrops no)
	)
	(paper "A4")
	(title_block
		(title "OCuLink to 10GbE adapter")
		(date "2026-02-23")
		(rev "1.1.0")
		(company "Antmicro Ltd")
		(comment 1 "www.antmicro.com")
		(comment 9 "footprints 485-489 of 510")
	)
	(layers
		(0 "F.Cu" signal)
		(4 "In1.Cu" signal)
		(6 "In2.Cu" signal)
		(8 "In3.Cu" signal)
		(10 "In4.Cu" signal)
		(12 "In5.Cu" signal)
		(14 "In6.Cu" signal)
		(2 "B.Cu" signal)
		(9 "F.Adhes" user "F.Adhesive")
		(11 "B.Adhes" user "B.Adhesive")
		(13 "F.Paste" user)
		(15 "B.Paste" user)
		(5 "F.SilkS" user "F.Silkscreen")
		(7 "B.SilkS" user "B.Silkscreen")
		(1 "F.Mask" user)
		(3 "B.Mask" user)
		(17 "Dwgs.User" user "User.Drawings")
		(19 "Cmts.User" user "User.Comments")
		(21 "Eco1.User" user "User.Eco1")
		(23 "Eco2.User" user "User.Eco2")
		(25 "Edge.Cuts" user)
		(27 "Margin" user)
		(31 "F.CrtYd" user "F.Courtyard")
		(29 "B.CrtYd" user "B.Courtyard")
		(35 "F.Fab" user)
		(33 "B.Fab" user)
	)
	(footprint "antmicro-footprints:C_0402_1005Metric"
		(layer "B.Cu")
		(at 77.67 107.9 -90)
		(descr "Capacitor SMD 0402")
		(tags "capacitor SMD 0402")
		(property "Reference" "C169"
			(at 0.84 -0.33 90)
			(layer "B.SilkS")
			(effects
				(font
					(size 0.7 0.7)
					(thickness 0.15)
				)
				(justify left bottom mirror)
			)
		)
		(property "Value" "C_1u_25V_0402"
			(at -1.022927 -2.155213 90)
			(layer "B.Fab")
			(hide yes)
			(effects
				(font
					(size 0.7 0.7)
					(thickness 0.15)
				)
				(justify left bottom mirror)
			)
		)
		(property "Datasheet" "https://www.murata.com/products/productdetail?partno=GRM155R61E105KE11%23"
			(at 0 0 90)
			(layer "B.Fab")
			(hide yes)
			(effects
				(font
					(size 1.27 1.27)
					(thickness 0.15)
				)
				(justify mirror)
			)
		)
		(property "Description" "SMD Multilayer Ceramic Capacitor, 1 µF, 25 V, 0402 [1005 Metric], ± 10%, X5R, GRM Series"
			(at 0 0 90)
			(layer "B.Fab")
			(hide yes)
			(effects
				(font
					(size 1.27 1.27)
					(thickness 0.15)
				)
				(justify mirror)
			)
		)
		(property "MPN" "GRM155R61E105KE11J"
			(at 0 0 270)
			(unlocked yes)
			(layer "B.Fab")
			(hide yes)
			(effects
				(font
					(size 1 1)
					(thickness 0.15)
				)
				(justify mirror)
			)
		)
		(property "Manufacturer" "Murata"
			(at 0 0 270)
			(unlocked yes)
			(layer "B.Fab")
			(hide yes)
			(effects
				(font
					(size 1 1)
					(thickness 0.15)
				)
				(justify mirror)
			)
		)
		(property "License" "Apache-2.0"
			(at 0 0 270)
			(unlocked yes)
			(layer "B.Fab")
			(hide yes)
			(effects
				(font
					(size 1 1)
					(thickness 0.15)
				)
				(justify mirror)
			)
		)
		(property "Author" "Antmicro"
			(at 0 0 270)
			(unlocked yes)
			(layer "B.Fab")
			(hide yes)
			(effects
				(font
					(size 1 1)
					(thickness 0.15)
				)
				(justify mirror)
			)
		)
		(property "Val" "1u"
			(at 0 0 270)
			(unlocked yes)
			(layer "B.Fab")
			(hide yes)
			(effects
				(font
					(size 1 1)
					(thickness 0.15)
				)
				(justify mirror)
			)
		)
		(property "Voltage" "25V"
			(at 0 0 270)
			(unlocked yes)
			(layer "B.Fab")
			(hide yes)
			(effects
				(font
					(size 1 1)
					(thickness 0.15)
				)
				(justify mirror)
			)
		)
		(property "Dielectric" "X5R"
			(at 0 0 270)
			(unlocked yes)
			(layer "B.Fab")
			(hide yes)
			(effects
				(font
					(size 1 1)
					(thickness 0.15)
				)
				(justify mirror)
			)
		)
		(sheetname "/X710-AT2 power/")
		(sheetfile "x710-at2-power.kicad_sch")
		(attr smd)
		(fp_rect
			(start -0.925 0.47)
			(end 0.925 -0.47)
			(stroke
				(width 0.05)
				(type default)
			)
			(fill no)
			(layer "B.CrtYd")
		)
		(fp_line
			(start -0.494 0.25)
			(end 0.504 0.25)
			(stroke
				(width 0.15)
				(type solid)
			)
			(layer "B.Fab")
		)
		(fp_line
			(start 0.504 0.25)
			(end 0.504 -0.248)
			(stroke
				(width 0.15)
				(type solid)
			)
			(layer "B.Fab")
		)
		(fp_line
			(start -0.494 -0.248)
			(end -0.494 0.25)
			(stroke
				(width 0.15)
				(type solid)
			)
			(layer "B.Fab")
		)
		(fp_line
			(start 0.504 -0.248)
			(end -0.494 -0.248)
			(stroke
				(width 0.15)
				(type solid)
			)
			(layer "B.Fab")
		)
		(pad "1" smd roundrect
			(at -0.48 0 270)
			(size 0.59 0.64)
			(layers "B.Cu" "B.Mask" "B.Paste")
			(roundrect_rratio 0.25)
			(net 28 "GND")
			(pintype "passive")
		)
		(pad "2" smd roundrect
			(at 0.48 0 270)
			(size 0.59 0.64)
			(layers "B.Cu" "B.Mask" "B.Paste")
			(roundrect_rratio 0.25)
			(net 5 "P0_AVDDL")
			(pintype "passive")
		)
	)
	(footprint "antmicro-footprints:R_0402_1005Metric"
		(layer "B.Cu")
		(at 91.7 104.45)
		(descr "Resistor SMD 0402")
		(tags "resistor SMD 0402")
		(property "Reference" "R76"
			(at 0.91 -0.44 0)
			(layer "B.SilkS")
			(effects
				(font
					(size 0.7 0.7)
					(thickness 0.15)
				)
				(justify right top mirror)
			)
		)
		(property "Value" "R_8k2_0402"
			(at -1.011843 -1.772046 0)
			(layer "B.Fab")
			(hide yes)
			(effects
				(font
					(size 0.7 0.7)
					(thickness 0.15)
				)
				(justify right top mirror)
			)
		)
		(property "Datasheet" "https://www.bourns.com/docs/product-datasheets/cr.pdf"
			(at 0 0 0)
			(layer "B.Fab")
			(hide yes)
			(effects
				(font
					(size 1.27 1.27)
					(thickness 0.15)
				)
				(justify mirror)
			)
		)
		(property "Description" "SMD Chip Resistor"
			(at 0 0 0)
			(layer "B.Fab")
			(hide yes)
			(effects
				(font
					(size 1.27 1.27)
					(thickness 0.15)
				)
				(justify mirror)
			)
		)
		(property "MPN" "CR0402-FX-8201GLF"
			(at 0 0 0)
			(unlocked yes)
			(layer "B.Fab")
			(hide yes)
			(effects
				(font
					(size 1 1)
					(thickness 0.15)
				)
				(justify mirror)
			)
		)
		(property "Manufacturer" "Bourns"
			(at 0 0 0)
			(unlocked yes)
			(layer "B.Fab")
			(hide yes)
			(effects
				(font
					(size 1 1)
					(thickness 0.15)
				)
				(justify mirror)
			)
		)
		(property "License" "Apache-2.0"
			(at 0 0 0)
			(unlocked yes)
			(layer "B.Fab")
			(hide yes)
			(effects
				(font
					(size 1 1)
					(thickness 0.15)
				)
				(justify mirror)
			)
		)
		(property "Author" "Antmicro"
			(at 0 0 0)
			(unlocked yes)
			(layer "B.Fab")
			(hide yes)
			(effects
				(font
					(size 1 1)
					(thickness 0.15)
				)
				(justify mirror)
			)
		)
		(property "Val" "8k2"
			(at 0 0 0)
			(unlocked yes)
			(layer "B.Fab")
			(hide yes)
			(effects
				(font
					(size 1 1)
					(thickness 0.15)
				)
				(justify mirror)
			)
		)
		(property "Tolerance" "1%"
			(at 0 0 0)
			(unlocked yes)
			(layer "B.Fab")
			(hide yes)
			(effects
				(font
					(size 1 1)
					(thickness 0.15)
				)
				(justify mirror)
			)
		)
		(sheetname "/X710-AT2 10GbE/")
		(sheetfile "x710-at2-10gbe.kicad_sch")
		(attr smd)
		(fp_rect
			(start -0.925 0.47)
			(end 0.925 -0.47)
			(stroke
				(width 0.05)
				(type default)
			)
			(fill no)
			(layer "B.CrtYd")
		)
		(fp_rect
			(start -0.5 0.25)
			(end 0.5 -0.25)
			(stroke
				(width 0.15)
				(type solid)
			)
			(fill no)
			(layer "B.Fab")
		)
		(pad "1" smd roundrect
			(at -0.48 0)
			(size 0.59 0.64)
			(layers "B.Cu" "B.Mask" "B.Paste")
			(roundrect_rratio 0.25)
			(net 85 "/X710-AT2 10GbE/OSC_SEL")
			(pintype "passive")
		)
		(pad "2" smd roundrect
			(at 0.48 0)
			(size 0.59 0.64)
			(layers "B.Cu" "B.Mask" "B.Paste")
			(roundrect_rratio 0.25)
			(net 7 "+3V3")
			(pintype "passive")
		)
	)
	(footprint "antmicro-footprints:C_0402_1005Metric"
		(layer "B.Cu")
		(at 76 105.05 90)
		(descr "Capacitor SMD 0402")
		(tags "capacitor SMD 0402")
		(property "Reference" "C189"
			(at -1.21 -1.37 90)
			(layer "B.SilkS")
			(effects
				(font
					(size 0.7 0.7)
					(thickness 0.15)
				)
				(justify right top mirror)
			)
		)
		(property "Value" "C_1u_25V_0402"
			(at -1.022927 -2.155213 90)
			(layer "B.Fab")
			(hide yes)
			(effects
				(font
					(size 0.7 0.7)
					(thickness 0.15)
				)
				(justify right top mirror)
			)
		)
		(property "Datasheet" "https://www.murata.com/products/productdetail?partno=GRM155R61E105KE11%23"
			(at 0 0 90)
			(layer "B.Fab")
			(hide yes)
			(effects
				(font
					(size 1.27 1.27)
					(thickness 0.15)
				)
				(justify mirror)
			)
		)
		(property "Description" "SMD Multilayer Ceramic Capacitor, 1 µF, 25 V, 0402 [1005 Metric], ± 10%, X5R, GRM Series"
			(at 0 0 90)
			(layer "B.Fab")
			(hide yes)
			(effects
				(font
					(size 1.27 1.27)
					(thickness 0.15)
				)
				(justify mirror)
			)
		)
		(property "MPN" "GRM155R61E105KE11J"
			(at 0 0 90)
			(unlocked yes)
			(layer "B.Fab")
			(hide yes)
			(effects
				(font
					(size 1 1)
					(thickness 0.15)
				)
				(justify mirror)
			)
		)
		(property "Manufacturer" "Murata"
			(at 0 0 90)
			(unlocked yes)
			(layer "B.Fab")
			(hide yes)
			(effects
				(font
					(size 1 1)
					(thickness 0.15)
				)
				(justify mirror)
			)
		)
		(property "License" "Apache-2.0"
			(at 0 0 90)
			(unlocked yes)
			(layer "B.Fab")
			(hide yes)
			(effects
				(font
					(size 1 1)
					(thickness 0.15)
				)
				(justify mirror)
			)
		)
		(property "Author" "Antmicro"
			(at 0 0 90)
			(unlocked yes)
			(layer "B.Fab")
			(hide yes)
			(effects
				(font
					(size 1 1)
					(thickness 0.15)
				)
				(justify mirror)
			)
		)
		(property "Val" "1u"
			(at 0 0 90)
			(unlocked yes)
			(layer "B.Fab")
			(hide yes)
			(effects
				(font
					(size 1 1)
					(thickness 0.15)
				)
				(justify mirror)
			)
		)
		(property "Voltage" "25V"
			(at 0 0 90)
			(unlocked yes)
			(layer "B.Fab")
			(hide yes)
			(effects
				(font
					(size 1 1)
					(thickness 0.15)
				)
				(justify mirror)
			)
		)
		(property "Dielectric" "X5R"
			(at 0 0 90)
			(unlocked yes)
			(layer "B.Fab")
			(hide yes)
			(effects
				(font
					(size 1 1)
					(thickness 0.15)
				)
				(justify mirror)
			)
		)
		(sheetname "/X710-AT2 power/")
		(sheetfile "x710-at2-power.kicad_sch")
		(attr smd)
		(fp_rect
			(start -0.925 0.47)
			(end 0.925 -0.47)
			(stroke
				(width 0.05)
				(type default)
			)
			(fill no)
			(layer "B.CrtYd")
		)
		(fp_line
			(start 0.504 -0.248)
			(end -0.494 -0.248)
			(stroke
				(width 0.15)
				(type solid)
			)
			(layer "B.Fab")
		)
		(fp_line
			(start -0.494 -0.248)
			(end -0.494 0.25)
			(stroke
				(width 0.15)
				(type solid)
			)
			(layer "B.Fab")
		)
		(fp_line
			(start 0.504 0.25)
			(end 0.504 -0.248)
			(stroke
				(width 0.15)
				(type solid)
			)
			(layer "B.Fab")
		)
		(fp_line
			(start -0.494 0.25)
			(end 0.504 0.25)
			(stroke
				(width 0.15)
				(type solid)
			)
			(layer "B.Fab")
		)
		(pad "1" smd roundrect
			(at -0.48 0 90)
			(size 0.59 0.64)
			(layers "B.Cu" "B.Mask" "B.Paste")
			(roundrect_rratio 0.25)
			(net 28 "GND")
			(pintype "passive")
		)
		(pad "2" smd roundrect
			(at 0.48 0 90)
			(size 0.59 0.64)
			(layers "B.Cu" "B.Mask" "B.Paste")
			(roundrect_rratio 0.25)
			(net 27 "PLL_VDD")
			(pintype "passive")
		)
	)
	(footprint "antmicro-footprints:C_0402_1005Metric"
		(layer "B.Cu")
		(at 87.225 96.45 90)
		(descr "Capacitor SMD 0402")
		(tags "capacitor SMD 0402")
		(property "Reference" "C107"
			(at 14.36 0.397657 270)
			(layer "B.SilkS")
			(effects
				(font
					(size 0.7 0.7)
					(thickness 0.15)
				)
				(justify left bottom mirror)
			)
		)
		(property "Value" "C_1u_25V_0402"
			(at -1.022927 -2.155213 270)
			(layer "B.Fab")
			(hide yes)
			(effects
				(font
					(size 0.7 0.7)
					(thickness 0.15)
				)
				(justify left bottom mirror)
			)
		)
		(property "Datasheet" "https://www.murata.com/products/productdetail?partno=GRM155R61E105KE11%23"
			(at 0 0 270)
			(layer "B.Fab")
			(hide yes)
			(effects
				(font
					(size 1.27 1.27)
					(thickness 0.15)
				)
				(justify mirror)
			)
		)
		(property "Description" "SMD Multilayer Ceramic Capacitor, 1 µF, 25 V, 0402 [1005 Metric], ± 10%, X5R, GRM Series"
			(at 0 0 270)
			(layer "B.Fab")
			(hide yes)
			(effects
				(font
					(size 1.27 1.27)
					(thickness 0.15)
				)
				(justify mirror)
			)
		)
		(property "MPN" "GRM155R61E105KE11J"
			(at 0 0 90)
			(unlocked yes)
			(layer "B.Fab")
			(hide yes)
			(effects
				(font
					(size 1 1)
					(thickness 0.15)
				)
				(justify mirror)
			)
		)
		(property "Manufacturer" "Murata"
			(at 0 0 90)
			(unlocked yes)
			(layer "B.Fab")
			(hide yes)
			(effects
				(font
					(size 1 1)
					(thickness 0.15)
				)
				(justify mirror)
			)
		)
		(property "License" "Apache-2.0"
			(at 0 0 90)
			(unlocked yes)
			(layer "B.Fab")
			(hide yes)
			(effects
				(font
					(size 1 1)
					(thickness 0.15)
				)
				(justify mirror)
			)
		)
		(property "Author" "Antmicro"
			(at 0 0 90)
			(unlocked yes)
			(layer "B.Fab")
			(hide yes)
			(effects
				(font
					(size 1 1)
					(thickness 0.15)
				)
				(justify mirror)
			)
		)
		(property "Val" "1u"
			(at 0 0 90)
			(unlocked yes)
			(layer "B.Fab")
			(hide yes)
			(effects
				(font
					(size 1 1)
					(thickness 0.15)
				)
				(justify mirror)
			)
		)
		(property "Voltage" "25V"
			(at 0 0 90)
			(unlocked yes)
			(layer "B.Fab")
			(hide yes)
			(effects
				(font
					(size 1 1)
					(thickness 0.15)
				)
				(justify mirror)
			)
		)
		(property "Dielectric" "X5R"
			(at 0 0 90)
			(unlocked yes)
			(layer "B.Fab")
			(hide yes)
			(effects
				(font
					(size 1 1)
					(thickness 0.15)
				)
				(justify mirror)
			)
		)
		(sheetname "/X710-AT2 power/")
		(sheetfile "x710-at2-power.kicad_sch")
		(attr smd)
		(fp_rect
			(start -0.925 0.47)
			(end 0.925 -0.47)
			(stroke
				(width 0.05)
				(type default)
			)
			(fill no)
			(layer "B.CrtYd")
		)
		(fp_line
			(start 0.504 -0.248)
			(end -0.494 -0.248)
			(stroke
				(width 0.15)
				(type solid)
			)
			(layer "B.Fab")
		)
		(fp_line
			(start -0.494 -0.248)
			(end -0.494 0.25)
			(stroke
				(width 0.15)
				(type solid)
			)
			(layer "B.Fab")
		)
		(fp_line
			(start 0.504 0.25)
			(end 0.504 -0.248)
			(stroke
				(width 0.15)
				(type solid)
			)
			(layer "B.Fab")
		)
		(fp_line
			(start -0.494 0.25)
			(end 0.504 0.25)
			(stroke
				(width 0.15)
				(type solid)
			)
			(layer "B.Fab")
		)
		(pad "1" smd roundrect
			(at -0.48 0 90)
			(size 0.59 0.64)
			(layers "B.Cu" "B.Mask" "B.Paste")
			(roundrect_rratio 0.25)
			(net 28 "GND")
			(pintype "passive")
		)
		(pad "2" smd roundrect
			(at 0.48 0 90)
			(size 0.59 0.64)
			(layers "B.Cu" "B.Mask" "B.Paste")
			(roundrect_rratio 0.25)
			(net 9 "VCCD")
			(pintype "passive")
		)
	)
	(footprint "antmicro-footprints:C_0402_1005Metric"
		(layer "B.Cu")
		(at 83.4 107.895 -90)
		(descr "Capacitor SMD 0402")
		(tags "capacitor SMD 0402")
		(property "Reference" "C175"
			(at 0.805 -0.355 90)
			(layer "B.SilkS")
			(effects
				(font
					(size 0.7 0.7)
					(thickness 0.15)
				)
				(justify left bottom mirror)
			)
		)
		(property "Value" "C_1u_25V_0402"
			(at -1.022927 -2.155213 90)
			(layer "B.Fab")
			(hide yes)
			(effects
				(font
					(size 0.7 0.7)
					(thickness 0.15)
				)
				(justify left bottom mirror)
			)
		)
		(property "Datasheet" "https://www.murata.com/products/productdetail?partno=GRM155R61E105KE11%23"
			(at 0 0 90)
			(layer "B.Fab")
			(hide yes)
			(effects
				(font
					(size 1.27 1.27)
					(thickness 0.15)
				)
				(justify mirror)
			)
		)
		(property "Description" "SMD Multilayer Ceramic Capacitor, 1 µF, 25 V, 0402 [1005 Metric], ± 10%, X5R, GRM Series"
			(at 0 0 90)
			(layer "B.Fab")
			(hide yes)
			(effects
				(font
					(size 1.27 1.27)
					(thickness 0.15)
				)
				(justify mirror)
			)
		)
		(property "MPN" "GRM155R61E105KE11J"
			(at 0 0 270)
			(unlocked yes)
			(layer "B.Fab")
			(hide yes)
			(effects
				(font
					(size 1 1)
					(thickness 0.15)
				)
				(justify mirror)
			)
		)
		(property "Manufacturer" "Murata"
			(at 0 0 270)
			(unlocked yes)
			(layer "B.Fab")
			(hide yes)
			(effects
				(font
					(size 1 1)
					(thickness 0.15)
				)
				(justify mirror)
			)
		)
		(property "License" "Apache-2.0"
			(at 0 0 270)
			(unlocked yes)
			(layer "B.Fab")
			(hide yes)
			(effects
				(font
					(size 1 1)
					(thickness 0.15)
				)
				(justify mirror)
			)
		)
		(property "Author" "Antmicro"
			(at 0 0 270)
			(unlocked yes)
			(layer "B.Fab")
			(hide yes)
			(effects
				(font
					(size 1 1)
					(thickness 0.15)
				)
				(justify mirror)
			)
		)
		(property "Val" "1u"
			(at 0 0 270)
			(unlocked yes)
			(layer "B.Fab")
			(hide yes)
			(effects
				(font
					(size 1 1)
					(thickness 0.15)
				)
				(justify mirror)
			)
		)
		(property "Voltage" "25V"
			(at 0 0 270)
			(unlocked yes)
			(layer "B.Fab")
			(hide yes)
			(effects
				(font
					(size 1 1)
					(thickness 0.15)
				)
				(justify mirror)
			)
		)
		(property "Dielectric" "X5R"
			(at 0 0 270)
			(unlocked yes)
			(layer "B.Fab")
			(hide yes)
			(effects
				(font
					(size 1 1)
					(thickness 0.15)
				)
				(justify mirror)
			)
		)
		(sheetname "/X710-AT2 power/")
		(sheetfile "x710-at2-power.kicad_sch")
		(attr smd)
		(fp_rect
			(start -0.925 0.47)
			(end 0.925 -0.47)
			(stroke
				(width 0.05)
				(type default)
			)
			(fill no)
			(layer "B.CrtYd")
		)
		(fp_line
			(start -0.494 0.25)
			(end 0.504 0.25)
			(stroke
				(width 0.15)
				(type solid)
			)
			(layer "B.Fab")
		)
		(fp_line
			(start 0.504 0.25)
			(end 0.504 -0.248)
			(stroke
				(width 0.15)
				(type solid)
			)
			(layer "B.Fab")
		)
		(fp_line
			(start -0.494 -0.248)
			(end -0.494 0.25)
			(stroke
				(width 0.15)
				(type solid)
			)
			(layer "B.Fab")
		)
		(fp_line
			(start 0.504 -0.248)
			(end -0.494 -0.248)
			(stroke
				(width 0.15)
				(type solid)
			)
			(layer "B.Fab")
		)
		(pad "1" smd roundrect
			(at -0.48 0 270)
			(size 0.59 0.64)
			(layers "B.Cu" "B.Mask" "B.Paste")
			(roundrect_rratio 0.25)
			(net 28 "GND")
			(pintype "passive")
		)
		(pad "2" smd roundrect
			(at 0.48 0 270)
			(size 0.59 0.64)
			(layers "B.Cu" "B.Mask" "B.Paste")
			(roundrect_rratio 0.25)
			(net 14 "P1_AVDDL")
			(pintype "passive")
		)
	)
)
